(kicad_pcb
	(version 20260206)
	(generator "pcbnew")
	(generator_version "10.0")
	(general
		(thickness 1.6)
		(legacy_teardrops no)
	)
	(paper "A4")
	(title_block
		(title "v1-chassis-manager — T6M_CM_d_v01_1031_1645.brd")
		(comment 1 "Open CloudServer (Microsoft) / footprints 1496-1498 of 2512")
	)
	(layers
		(0 "F.Cu" signal "TOP")
		(4 "In1.Cu" signal "GND1")
		(6 "In2.Cu" signal "IN1")
		(8 "In3.Cu" signal "VCC1")
		(10 "In4.Cu" signal "VCC2")
		(12 "In5.Cu" signal "GND2")
		(14 "In6.Cu" signal "IN2")
		(16 "In7.Cu" signal "IN3")
		(18 "In8.Cu" signal "GND3")
		(2 "B.Cu" signal "BOTTOM")
		(9 "F.Adhes" user "F.Adhesive")
		(11 "B.Adhes" user "B.Adhesive")
		(13 "F.Paste" user "Package Geometry/Pastemask Top")
		(15 "B.Paste" user "Package Geometry/Pastemask Bottom")
		(5 "F.SilkS" user "Ref Des/Silkscreen Top")
		(7 "B.SilkS" user "Ref Des/Silkscreen Bottom")
		(1 "F.Mask" user "Board Geometry/Soldermask Top")
		(3 "B.Mask" user "Board Geometry/Soldermask Bottom")
		(17 "Dwgs.User" user "User.Drawings")
		(19 "Cmts.User" user "User.Comments")
		(21 "Eco1.User" user "User.Eco1")
		(23 "Eco2.User" user "User.Eco2")
		(25 "Edge.Cuts" user "Board Geometry/Outline")
		(27 "Margin" user)
		(31 "F.CrtYd" user "Package Geometry/Place Bound Top")
		(29 "B.CrtYd" user "Package Geometry/Place Bound Bottom")
		(35 "F.Fab" user "Ref Des/Assembly Top")
		(33 "B.Fab" user "Ref Des/Assembly Bottom")
	)
	(footprint ""
		(layer "F.Cu")
		(at 107.471464 -134.897876 180)
		(property "Reference" "PU8"
			(at -0.989076 3.710432 0)
			(unlocked yes)
			(layer "F.SilkS")
			(effects
				(font
					(size 0.7874 0.5842)
					(thickness 0.1524)
				)
				(justify left)
			)
		)
		(property "Value" ""
			(at 0 0 180)
			(layer "F.Fab")
			(effects
				(font
					(size 1.27 1.27)
				)
			)
		)
		(duplicate_pad_numbers_are_jumpers no)
		(fp_line
			(start 4.162044 -1.800098)
			(end 3.146044 -1.800098)
			(stroke
				(width 0.1524)
				(type default)
			)
			(layer "F.SilkS")
		)
		(fp_line
			(start 3.657092 0.199898)
			(end 3.149092 0.199898)
			(stroke
				(width 0.1524)
				(type default)
			)
			(layer "F.SilkS")
		)
		(fp_line
			(start 2.525014 2.525014)
			(end 2.021586 2.525014)
			(stroke
				(width 0.1524)
				(type default)
			)
			(layer "F.SilkS")
		)
		(fp_line
			(start 2.525014 2.022602)
			(end 2.525014 2.525014)
			(stroke
				(width 0.1524)
				(type default)
			)
			(layer "F.SilkS")
		)
		(fp_line
			(start 2.525014 -2.525014)
			(end 2.525014 -2.028698)
			(stroke
				(width 0.1524)
				(type default)
			)
			(layer "F.SilkS")
		)
		(fp_line
			(start 2.021586 -2.525014)
			(end 2.525014 -2.525014)
			(stroke
				(width 0.1524)
				(type default)
			)
			(layer "F.SilkS")
		)
		(fp_line
			(start 1.800098 3.1496)
			(end 1.800098 4.1656)
			(stroke
				(width 0.1524)
				(type default)
			)
			(layer "F.SilkS")
		)
		(fp_line
			(start -0.199898 3.149092)
			(end -0.199898 3.657092)
			(stroke
				(width 0.1524)
				(type default)
			)
			(layer "F.SilkS")
		)
		(fp_line
			(start -1.800098 -4.161536)
			(end -1.800098 -3.145536)
			(stroke
				(width 0.1524)
				(type default)
			)
			(layer "F.SilkS")
		)
		(fp_line
			(start -2.029714 2.525014)
			(end -2.525014 2.525014)
			(stroke
				(width 0.1524)
				(type default)
			)
			(layer "F.SilkS")
		)
		(fp_line
			(start -2.525014 2.525014)
			(end -2.525014 2.022602)
			(stroke
				(width 0.1524)
				(type default)
			)
			(layer "F.SilkS")
		)
		(fp_line
			(start -2.525014 -2.028698)
			(end -2.525014 -2.525014)
			(stroke
				(width 0.1524)
				(type default)
			)
			(layer "F.SilkS")
		)
		(fp_line
			(start -2.525014 -2.525014)
			(end -2.029714 -2.525014)
			(stroke
				(width 0.1524)
				(type default)
			)
			(layer "F.SilkS")
		)
		(fp_line
			(start -3.143758 -0.199898)
			(end -3.651758 -0.199898)
			(stroke
				(width 0.1524)
				(type default)
			)
			(layer "F.SilkS")
		)
		(fp_line
			(start -3.146044 1.800098)
			(end -4.162044 1.800098)
			(stroke
				(width 0.1524)
				(type default)
			)
			(layer "F.SilkS")
		)
		(fp_poly
			(pts
				(xy -3.085592 -1.800098) (xy -3.771392 -2.104898) (xy -3.771392 -1.495298)
			)
			(stroke
				(width 0)
				(type default)
			)
			(fill yes)
			(layer "F.SilkS")
		)
		(fp_poly
			(pts
				(xy -2.525014 2.525014) (xy -1.940814 2.525014) (xy -1.940814 3.076702) (xy 1.945386 3.076702) (xy 1.945386 2.525014)
				(xy 2.525014 2.525014) (xy 2.525014 1.959102) (xy 3.062986 1.959102) (xy 3.062986 -1.952498) (xy 2.525014 -1.952498)
				(xy 2.525014 -2.525014) (xy 1.945386 -2.525014) (xy 1.945386 -3.070098) (xy -1.940814 -3.070098)
				(xy -1.940814 -2.525014) (xy -2.525014 -2.525014) (xy -2.525014 -1.952498) (xy -3.060954 -1.952498)
				(xy -3.060954 1.959102) (xy -2.525014 1.959102)
			)
			(stroke
				(width 0)
				(type default)
			)
			(fill no)
			(layer "F.CrtYd")
		)
		(fp_line
			(start 4.162044 -1.800098)
			(end 3.146044 -1.800098)
			(stroke
				(width 0.1)
				(type default)
			)
			(layer "F.Fab")
		)
		(fp_line
			(start 3.657092 0.199898)
			(end 3.149092 0.199898)
			(stroke
				(width 0.1)
				(type default)
			)
			(layer "F.Fab")
		)
		(fp_line
			(start 2.525014 2.525014)
			(end -2.525014 2.525014)
			(stroke
				(width 0.1)
				(type default)
			)
			(layer "F.Fab")
		)
		(fp_line
			(start 2.525014 -2.525014)
			(end 2.525014 2.525014)
			(stroke
				(width 0.1)
				(type default)
			)
			(layer "F.Fab")
		)
		(fp_line
			(start 1.800098 3.1496)
			(end 1.800098 4.1656)
			(stroke
				(width 0.1)
				(type default)
			)
			(layer "F.Fab")
		)
		(fp_line
			(start 0.199898 -3.654044)
			(end 0.199898 -3.146044)
			(stroke
				(width 0.1)
				(type default)
			)
			(layer "F.Fab")
		)
		(fp_line
			(start -0.199898 3.149092)
			(end -0.199898 3.657092)
			(stroke
				(width 0.1)
				(type default)
			)
			(layer "F.Fab")
		)
		(fp_line
			(start -1.800098 -4.161536)
			(end -1.800098 -3.145536)
			(stroke
				(width 0.1)
				(type default)
			)
			(layer "F.Fab")
		)
		(fp_line
			(start -2.525014 2.525014)
			(end -2.525014 -2.525014)
			(stroke
				(width 0.1)
				(type default)
			)
			(layer "F.Fab")
		)
		(fp_line
			(start -2.525014 -2.525014)
			(end 2.525014 -2.525014)
			(stroke
				(width 0.1)
				(type default)
			)
			(layer "F.Fab")
		)
		(fp_line
			(start -3.143758 -0.199898)
			(end -3.651758 -0.199898)
			(stroke
				(width 0.1)
				(type default)
			)
			(layer "F.Fab")
		)
		(fp_line
			(start -3.146044 1.800098)
			(end -4.162044 1.800098)
			(stroke
				(width 0.1)
				(type default)
			)
			(layer "F.Fab")
		)
		(fp_poly
			(pts
				(xy -3.085592 -1.800098) (xy -3.771392 -2.104898) (xy -3.771392 -1.495298)
			)
			(stroke
				(width 0)
				(type default)
			)
			(fill yes)
			(layer "F.Fab")
		)
		(fp_text user "30"
			(at 4.251706 -1.356614 0)
			(unlocked yes)
			(layer "F.SilkS")
			(effects
				(font
					(size 0.635 0.4064)
					(thickness 0.1524)
				)
				(justify left)
			)
		)
		(fp_text user "21"
			(at 3.979164 1.6256 0)
			(unlocked yes)
			(layer "F.SilkS")
			(effects
				(font
					(size 0.635 0.4064)
					(thickness 0.1524)
				)
				(justify left)
			)
		)
		(fp_text user "20"
			(at 3.64744 2.611374 0)
			(unlocked yes)
			(layer "F.SilkS")
			(effects
				(font
					(size 0.635 0.4064)
					(thickness 0.1524)
				)
				(justify left)
			)
		)
		(fp_text user "31"
			(at 2.902204 -3.089148 0)
			(unlocked yes)
			(layer "F.SilkS")
			(effects
				(font
					(size 0.635 0.4064)
					(thickness 0.1524)
				)
				(justify left)
			)
		)
		(fp_text user "40"
			(at -0.677164 -3.549142 0)
			(unlocked yes)
			(layer "F.SilkS")
			(effects
				(font
					(size 0.635 0.4064)
					(thickness 0.1524)
				)
				(justify left)
			)
		)
		(fp_text user "11"
			(at -2.017776 2.829052 0)
			(unlocked yes)
			(layer "F.SilkS")
			(effects
				(font
					(size 0.635 0.4064)
					(thickness 0.1524)
				)
				(justify left)
			)
		)
		(fp_text user "10"
			(at -3.087116 1.229614 0)
			(unlocked yes)
			(layer "F.SilkS")
			(effects
				(font
					(size 0.635 0.4064)
					(thickness 0.1524)
				)
				(justify left)
			)
		)
		(fp_text user "1"
			(at -3.214116 -2.677668 0)
			(unlocked yes)
			(layer "F.SilkS")
			(effects
				(font
					(size 0.7874 0.5842)
					(thickness 0.1524)
				)
				(justify left)
			)
		)
		(fp_text user "21"
			(at 2.787142 2.4892 180)
			(unlocked yes)
			(layer "F.Fab")
			(effects
				(font
					(size 0.7874 0.5842)
					(thickness 0.000001)
				)
				(justify left)
			)
		)
		(fp_text user "30"
			(at 2.714244 -2.49174 180)
			(unlocked yes)
			(layer "F.Fab")
			(effects
				(font
					(size 0.7874 0.5842)
					(thickness 0.000001)
				)
				(justify left)
			)
		)
		(fp_text user "20"
			(at 1.961896 3.435096 180)
			(unlocked yes)
			(layer "F.Fab")
			(effects
				(font
					(size 0.7874 0.5842)
					(thickness 0.000001)
				)
				(justify left)
			)
		)
		(fp_text user "31"
			(at 1.866646 -3.44424 180)
			(unlocked yes)
			(layer "F.Fab")
			(effects
				(font
					(size 0.7874 0.5842)
					(thickness 0.000001)
				)
				(justify left)
			)
		)
		(fp_text user "11"
			(at -3.085846 3.308096 180)
			(unlocked yes)
			(layer "F.Fab")
			(effects
				(font
					(size 0.7874 0.5842)
					(thickness 0.000001)
				)
				(justify left)
			)
		)
		(fp_text user "40"
			(at -3.336544 -3.193542 180)
			(unlocked yes)
			(layer "F.Fab")
			(effects
				(font
					(size 0.7874 0.5842)
					(thickness 0.000001)
				)
				(justify left)
			)
		)
		(fp_text user "1"
			(at -3.546094 -2.393442 180)
			(unlocked yes)
			(layer "F.Fab")
			(effects
				(font
					(size 0.7874 0.5842)
					(thickness 0.000001)
				)
				(justify left)
			)
		)
		(fp_text user "10"
			(at -4.085844 2.50825 180)
			(unlocked yes)
			(layer "F.Fab")
			(effects
				(font
					(size 0.7874 0.5842)
					(thickness 0.000001)
				)
				(justify left)
			)
		)
		(pad "1" smd rect
			(at -2.542794 -1.800098 90)
			(size 0.1778 0.9144)
			(layers "F.Cu" "F.Mask" "F.Paste")
			(net "VR_PVCCP_NODE1_BOOT1")
		)
		(pad "2" smd rect
			(at -2.525014 -1.400048 90)
			(size 0.1778 0.9652)
			(layers "F.Cu" "F.Mask" "F.Paste")
			(net "VR_PVCCP_NODE1_TONSET")
		)
		(pad "3" smd rect
			(at -2.525014 -0.999998 90)
			(size 0.1778 0.9652)
			(layers "F.Cu" "F.Mask" "F.Paste")
			(net "VR_PVCCP_NODE1_ISEN1P_CC")
		)
		(pad "4" smd rect
			(at -2.525014 -0.599948 90)
			(size 0.1778 0.9652)
			(layers "F.Cu" "F.Mask" "F.Paste")
			(net "ISENSE_PVCCP_NODE1_ISEN1N")
		)
		(pad "5" smd rect
			(at -2.525014 -0.199898 90)
			(size 0.1778 0.9652)
			(layers "F.Cu" "F.Mask" "F.Paste")
			(net "VR_PVCCP_NODE1_COMP")
		)
		(pad "6" smd rect
			(at -2.525014 0.199898 90)
			(size 0.1778 0.9652)
			(layers "F.Cu" "F.Mask" "F.Paste")
			(net "VR_PVCCP_NODE1_FB")
		)
		(pad "7" smd rect
			(at -2.525014 0.599948 90)
			(size 0.1778 0.9652)
			(layers "F.Cu" "F.Mask" "F.Paste")
			(net "VR_PVCCP_NODE1_RGND")
		)
		(pad "8" smd rect
			(at -2.525014 0.999998 90)
			(size 0.1778 0.9652)
			(layers "F.Cu" "F.Mask" "F.Paste")
			(net "AGND_PVCCP_NODE1")
		)
		(pad "9" smd rect
			(at -2.525014 1.400048 90)
			(size 0.1778 0.9652)
			(layers "F.Cu" "F.Mask" "F.Paste")
			(net "VR_PVCCP_NODE1_VCC")
		)
		(pad "10" smd rect
			(at -2.542794 1.800098 90)
			(size 0.1778 0.9144)
			(layers "F.Cu" "F.Mask" "F.Paste")
			(net "GND")
		)
		(pad "11" smd rect
			(at -1.800098 2.542794 180)
			(size 0.1778 0.9144)
			(layers "F.Cu" "F.Mask" "F.Paste")
			(net "VR_PVCCP_NODE1_SETINI")
		)
		(pad "12" smd rect
			(at -1.400048 2.525014 180)
			(size 0.1778 0.9652)
			(layers "F.Cu" "F.Mask" "F.Paste")
			(net "VR_PVCCP_NODE1_TEMPMAX")
		)
		(pad "13" smd rect
			(at -0.999998 2.525014 180)
			(size 0.1778 0.9652)
			(layers "F.Cu" "F.Mask" "F.Paste")
			(net "VR_PVCCP_NODE1_ICCMAX")
		)
		(pad "14" smd rect
			(at -0.599948 2.525014 180)
			(size 0.1778 0.9652)
			(layers "F.Cu" "F.Mask" "F.Paste")
			(net "P5V_STB_NODE1")
		)
		(pad "15" smd rect
			(at -0.199898 2.525014 180)
			(size 0.1778 0.9652)
			(layers "F.Cu" "F.Mask" "F.Paste")
			(net "VR_PVCCP_NODE1_TSEN")
		)
		(pad "16" smd rect
			(at 0.199898 2.525014 180)
			(size 0.1778 0.9652)
			(layers "F.Cu" "F.Mask" "F.Paste")
			(net "VR_PVCCP_NODE1_OCSET")
		)
		(pad "17" smd rect
			(at 0.599948 2.525014 180)
			(size 0.1778 0.9652)
			(layers "F.Cu" "F.Mask" "F.Paste")
			(net "VR_PVCCP_NODE1_VCC")
		)
		(pad "18" smd rect
			(at 0.999998 2.525014 180)
			(size 0.1778 0.9652)
			(layers "F.Cu" "F.Mask" "F.Paste")
			(net "P5V_STB_NODE1")
		)
		(pad "19" smd rect
			(at 1.400048 2.525014 180)
			(size 0.1778 0.9652)
			(layers "F.Cu" "F.Mask" "F.Paste")
			(net "VR_PVCCP_NODE1_IBIAS")
		)
		(pad "20" smd rect
			(at 1.800098 2.542794 180)
			(size 0.1778 0.9144)
			(layers "F.Cu" "F.Mask" "F.Paste")
			(net "H_CPU_NODE1_VR_HOT_L")
		)
		(pad "21" smd rect
			(at 2.542794 1.800098 90)
			(size 0.1778 0.9144)
			(layers "F.Cu" "F.Mask" "F.Paste")
			(net "PWRGD_NODE1_PVCCP_PG")
		)
		(pad "22" smd rect
			(at 2.525014 1.400048 90)
			(size 0.1778 0.9652)
			(layers "F.Cu" "F.Mask" "F.Paste")
			(net "GND")
		)
		(pad "23" smd rect
			(at 2.525014 0.999998 90)
			(size 0.1778 0.9652)
			(layers "F.Cu" "F.Mask" "F.Paste")
			(net "SVID_CPU_NODE1_PVCCP_ALERT_L")
		)
		(pad "24" smd rect
			(at 2.525014 0.599948 90)
			(size 0.1778 0.9652)
			(layers "F.Cu" "F.Mask" "F.Paste")
			(net "SVID_CPU_NODE1_DAT_R")
		)
		(pad "25" smd rect
			(at 2.525014 0.199898 90)
			(size 0.1778 0.9652)
			(layers "F.Cu" "F.Mask" "F.Paste")
			(net "SVID_CPU_NODE1_CLK_R")
		)
		(pad "26" smd rect
			(at 2.525014 -0.199898 90)
			(size 0.1778 0.9652)
			(layers "F.Cu" "F.Mask" "F.Paste")
			(net "GND")
		)
		(pad "27" smd rect
			(at 2.525014 -0.599948 90)
			(size 0.1778 0.9652)
			(layers "F.Cu" "F.Mask" "F.Paste")
			(net "Net_1697")
		)
		(pad "28" smd rect
			(at 2.525014 -0.999998 90)
			(size 0.1778 0.9652)
			(layers "F.Cu" "F.Mask" "F.Paste")
			(net "Net_1696")
		)
		(pad "29" smd rect
			(at 2.525014 -1.400048 90)
			(size 0.1778 0.9652)
			(layers "F.Cu" "F.Mask" "F.Paste")
			(net "P5V_STB_NODE1")
		)
		(pad "30" smd rect
			(at 2.542794 -1.800098 90)
			(size 0.1778 0.9144)
			(layers "F.Cu" "F.Mask" "F.Paste")
			(net "P5V_STB_NODE1")
		)
		(pad "31" smd rect
			(at 1.800098 -2.542794 180)
			(size 0.1778 0.9144)
			(layers "F.Cu" "F.Mask" "F.Paste")
			(net "GND")
		)
		(pad "32" smd rect
			(at 1.400048 -2.525014 180)
			(size 0.1778 0.9652)
			(layers "F.Cu" "F.Mask" "F.Paste")
			(net "VR_PVCCP_NODE1_EN")
		)
		(pad "33" smd rect
			(at 0.999998 -2.525014 180)
			(size 0.1778 0.9652)
			(layers "F.Cu" "F.Mask" "F.Paste")
			(net "Net_1695")
		)
		(pad "34" smd rect
			(at 0.599948 -2.525014 180)
			(size 0.1778 0.9652)
			(layers "F.Cu" "F.Mask" "F.Paste")
			(net "Net_1700")
		)
		(pad "35" smd rect
			(at 0.199898 -2.525014 180)
			(size 0.1778 0.9652)
			(layers "F.Cu" "F.Mask" "F.Paste")
			(net "Net_1699")
		)
		(pad "36" smd rect
			(at -0.199898 -2.525014 180)
			(size 0.1778 0.9652)
			(layers "F.Cu" "F.Mask" "F.Paste")
			(net "Net_1698")
		)
		(pad "37" smd rect
			(at -0.599948 -2.525014 180)
			(size 0.1778 0.9652)
			(layers "F.Cu" "F.Mask" "F.Paste")
			(net "VR_PVCCP_NODE1_PVCC")
		)
		(pad "38" smd rect
			(at -0.999998 -2.525014 180)
			(size 0.1778 0.9652)
			(layers "F.Cu" "F.Mask" "F.Paste")
			(net "VR_PVCCP_NODE1_LGATE1")
		)
		(pad "39" smd rect
			(at -1.400048 -2.525014 180)
			(size 0.1778 0.9652)
			(layers "F.Cu" "F.Mask" "F.Paste")
			(net "VR_PVCCP_NODE1_PHASE1")
		)
		(pad "40" smd rect
			(at -1.800098 -2.542794 180)
			(size 0.1778 0.9144)
			(layers "F.Cu" "F.Mask" "F.Paste")
			(net "VR_PVCCP_NODE1_UGATE1")
		)
		(pad "TH" smd rect
			(at 0 0 180)
			(size 3.4036 3.4036)
			(layers "F.Cu" "F.Mask" "F.Paste")
			(net "GND")
		)
		(zone
			(layer "F.Cu")
			(hatch none 0.5)
			(connect_pads
				(clearance 0)
			)
			(min_thickness 0.25)
			(keepout
				(tracks allowed)
				(vias not_allowed)
				(pads allowed)
				(copperpour not_allowed)
				(footprints allowed)
			)
			(placement
				(enabled no)
				(sheetname "")
			)
			(fill
				(thermal_gap 0.5)
				(thermal_bridge_width 0.5)
				(island_removal_mode 0)
			)
			(polygon
				(pts
					(xy 109.437678 -136.653778) (xy 109.437678 -132.919978) (xy 109.234478 -132.919978) (xy 105.500678 -132.919978)
					(xy 105.500678 -133.123178) (xy 105.500678 -136.882378) (xy 105.703878 -136.882378) (xy 109.437678 -136.882378)
					(xy 109.437678 -136.856978) (xy 109.437678 -136.679178) (xy 105.703878 -136.679178) (xy 105.703878 -136.653778)
					(xy 105.703878 -133.123178) (xy 109.234478 -133.123178) (xy 109.234478 -136.653778)
				)
			)
		)
	)
	(footprint ""
		(layer "F.Cu")
		(at 115.826032 -17.575276)
		(property "Reference" "R1242"
			(at -1.89992 1.406398 0)
			(unlocked yes)
			(layer "F.SilkS")
			(effects
				(font
					(size 0.7874 0.5842)
					(thickness 0.1524)
				)
				(justify left)
			)
		)
		(property "Value" ""
			(at 0 0 0)
			(layer "F.Fab")
			(effects
				(font
					(size 1.27 1.27)
				)
			)
		)
		(duplicate_pad_numbers_are_jumpers no)
		(fp_line
			(start -0.7874 -0.4064)
			(end 0.7874 -0.4064)
			(stroke
				(width 0.1524)
				(type default)
			)
			(layer "F.SilkS")
		)
		(fp_line
			(start -0.7874 0.4064)
			(end -0.7874 -0.4064)
			(stroke
				(width 0.1524)
				(type default)
			)
			(layer "F.SilkS")
		)
		(fp_line
			(start 0.7874 -0.4064)
			(end 0.7874 0.4064)
			(stroke
				(width 0.1524)
				(type default)
			)
			(layer "F.SilkS")
		)
		(fp_line
			(start 0.7874 0.4064)
			(end -0.7874 0.4064)
			(stroke
				(width 0.1524)
				(type default)
			)
			(layer "F.SilkS")
		)
		(fp_poly
			(pts
				(xy -0.508 0.2794) (xy -0.508 0.2286) (xy -0.635 0.2286) (xy -0.635 -0.254) (xy -0.5334 -0.254)
				(xy -0.5334 -0.2794) (xy 0.5334 -0.2794) (xy 0.5334 -0.254) (xy 0.635 -0.254) (xy 0.635 0.254) (xy 0.5334 0.254)
				(xy 0.5334 0.2794)
			)
			(stroke
				(width 0)
				(type default)
			)
			(fill no)
			(layer "F.CrtYd")
		)
		(pad "1" smd rect
			(at 0.40005 0)
			(size 0.4572 0.508)
			(layers "F.Cu" "F.Mask" "F.Paste")
			(net "GND")
		)
		(pad "2" smd rect
			(at -0.40005 0)
			(size 0.4572 0.508)
			(layers "F.Cu" "F.Mask" "F.Paste")
			(net "FM_CPLD_NODE1_PVTT_DDR_EN")
		)
	)
	(footprint ""
		(layer "F.Cu")
		(at 146.78152 -100.391468 -90)
		(property "Reference" ""
			(at 0 0 270)
			(layer "F.SilkS")
			(hide yes)
			(effects
				(font
					(size 1.27 1.27)
				)
			)
		)
		(property "Value" ""
			(at 0 0 270)
			(layer "F.Fab")
			(effects
				(font
					(size 1.27 1.27)
				)
			)
		)
		(duplicate_pad_numbers_are_jumpers no)
		(fp_poly
			(pts
				(arc
					(start 0 -1.4986)
					(mid 0 1.4986)
					(end 0 -1.4986)
				)
			)
			(stroke
				(width 0)
				(type default)
			)
			(fill no)
			(layer "F.CrtYd")
		)
		(pad "1" smd circle
			(at 0 0 270)
			(size 0.9906 0.9906)
			(layers "F.Cu" "F.Mask" "F.Paste")
			(net "Net_31")
		)
		(zone
			(layer "F.Cu")
			(hatch none 0.5)
			(connect_pads
				(clearance 0)
			)
			(min_thickness 0.25)
			(keepout
				(tracks not_allowed)
				(vias allowed)
				(pads allowed)
				(copperpour not_allowed)
				(footprints allowed)
			)
			(placement
				(enabled no)
				(sheetname "")
			)
			(fill
				(thermal_gap 0.5)
				(thermal_bridge_width 0.5)
				(island_removal_mode 0)
			)
			(polygon
				(pts
					(arc
						(start 148.40712 -100.391468)
						(mid 145.15592 -100.391468)
						(end 148.40712 -100.391468)
					)
				)
			)
		)
	)
)
